# S9S_MB_2U (Grand Teton) — schematic netlist excerpt (pin names and nets, part order shuffled) for the footprints in the layout excerpt that follows; sources: Cadence DE-HDL packaged netlist, KiCad conversion of 03242023_DA0F0TMBIJ0_F0T_Motherboard_J_brd_V01_OCP.brd

J15  SCONN288_ADR50017P130CC  SCONN288_ADR50017-P130CC IO  pkg DDR288S_1-1VXB  page 96
  VIN_BULK0  = P12V_S3_AUX_CPU0_NVDIMM
  RFU0  = TP_CHH_CPU0_DIMM1_FRU_0
  VIN_MGMT  = P3V3_AUX
  HSCL  = I3C_SPD_DDREFGH_CPU0_LVC1_SCL_6
  HSDA  = I3C_SPD_DDREFGH_CPU0_LVC1_SDA
  VSS0  = GND
  DQ0_A  = M_H_CPU0_SA_DQ<0>
  VSS1  = GND
  DQ1_A  = M_H_CPU0_SA_DQ<1>
  VSS2  = GND
  DQS0_A_T  = M_H_CPU0_SA_DQS_DP<0>
  DQS0_A_C  = M_H_CPU0_SA_DQS_DN<0>
  VSS3  = GND
  DQ4_A  = M_H_CPU0_SA_DQ<4>
  VSS4  = GND
  DQ5_A  = M_H_CPU0_SA_DQ<5>
  VSS5  = GND
  DQ8_A  = M_H_CPU0_SA_DQ<8>
  VSS6  = GND
  DQ9_A  = M_H_CPU0_SA_DQ<9>
  VSS7  = GND
  DQS1_A_T  = M_H_CPU0_SA_DQS_DP<1>
  DQS1_A_C  = M_H_CPU0_SA_DQS_DN<1>
  VSS8  = GND
  DQ12_A  = M_H_CPU0_SA_DQ<12>
  VSS9  = GND
  DQ13_A  = M_H_CPU0_SA_DQ<13>
  VSS10  = GND
  DQ16_A  = M_H_CPU0_SA_DQ<16>
  VSS11  = GND
  DQ17_A  = M_H_CPU0_SA_DQ<17>
  VSS12  = GND
  DQS2_A_T  = M_H_CPU0_SA_DQS_DP<2>
  DQS2_A_C  = M_H_CPU0_SA_DQS_DN<2>
  VSS13  = GND
  DQ20_A  = M_H_CPU0_SA_DQ<20>
  VSS14  = GND
  DQ21_A  = M_H_CPU0_SA_DQ<21>
  VSS15  = GND
  DQ24_A  = M_H_CPU0_SA_DQ<24>
  VSS16  = GND
  DQ25_A  = M_H_CPU0_SA_DQ<25>
  VSS17  = GND
  DQS3_A_T  = M_H_CPU0_SA_DQS_DP<3>
  DQS3_A_C  = M_H_CPU0_SA_DQS_DN<3>
  VSS18  = GND
  DQ28_A  = M_H_CPU0_SA_DQ<28>
  VSS19  = GND
  DQ29_A  = M_H_CPU0_SA_DQ<29>
  VSS20  = GND
  CB0_A  = M_H_CPU0_SA_CB<0>
  VSS21  = GND
  CB1_A  = M_H_CPU0_SA_CB<1>
  VSS22  = GND
  DQS4_A_T  = M_H_CPU0_SA_DQS_DP<4>
  DQS4_A_C  = M_H_CPU0_SA_DQS_DN<4>
  VSS23  = GND
  CB4_A  = M_H_CPU0_SA_CB<4>
  VSS24  = GND
  CB5_A  = M_H_CPU0_SA_CB<5>
  VSS25  = GND
  ALERT_N  = M_H_CPU0_ALERT_N
  VSS26  = GND
  CS0_A_N  = M_H_CPU0_SA_CS_N<0>
  VSS27  = GND
  CA0_A  = M_H_CPU0_SA_CA<0>
  VSS28  = GND
  CA2_A  = M_H_CPU0_SA_CA<2>
  VSS29  = GND
  CA4_A  = M_H_CPU0_SA_CA<4>
  VSS30  = GND
  CA6_A  = M_H_CPU0_SA_CA<6>
  VSS31  = GND
  PAR_A  = M_H_CPU0_SA_PAR
  VSS32  = GND
  CA0_B  = M_H_CPU0_SB_CA<0>
  VSS33  = GND
  CA2_B  = M_H_CPU0_SB_CA<2>
  VSS34  = GND
  CA4_B  = M_H_CPU0_SB_CA<4>
  VSS35  = GND
  CA6_B  = M_H_CPU0_SB_CA<6>
  VSS36  = GND
  CS0_B_N  = M_H_CPU0_SB_CS_N<0>
  VSS37  = GND
  \lbd||rsp_a_n\  = M_H_CPU0_SA_RSP<0>
  \lbs||rsp_b_n\  = M_H_CPU0_SB_RSP<0>
  VSS38  = GND
  CB4_B  = M_H_CPU0_SB_CB<4>
  VSS39  = GND
  CB5_B  = M_H_CPU0_SB_CB<5>
  VSS40  = GND
  \dqs9_b_t||tdqs9_b_t||dbi4_b_n\  = M_H_CPU0_SB_DQS_DP<9>
  \dqs9_b_c||tdqs9_b_c\  = M_H_CPU0_SB_DQS_DN<9>
  VSS41  = GND
  CB0_B  = M_H_CPU0_SB_CB<0>
  VSS42  = GND
  CB1_B  = M_H_CPU0_SB_CB<1>
  VSS43  = GND
  DQ0_B  = M_H_CPU0_SB_DQ<0>
  VSS44  = GND
  DQ1_B  = M_H_CPU0_SB_DQ<1>
  VSS45  = GND
  DQS0_B_T  = M_H_CPU0_SB_DQS_DP<0>
  DQS0_B_C  = M_H_CPU0_SB_DQS_DN<0>
  VSS46  = GND
  DQ4_B  = M_H_CPU0_SB_DQ<4>
  VSS47  = GND
  DQ5_B  = M_H_CPU0_SB_DQ<5>
  VSS48  = GND
  DQ8_B  = M_H_CPU0_SB_DQ<8>
  VSS49  = GND
  DQ9_B  = M_H_CPU0_SB_DQ<9>
  VSS50  = GND
  DQS1_B_T  = M_H_CPU0_SB_DQS_DP<1>
  DQS1_B_C  = M_H_CPU0_SB_DQS_DN<1>
  VSS51  = GND
  DQ12_B  = M_H_CPU0_SB_DQ<12>
  VSS52  = GND
  DQ13_B  = M_H_CPU0_SB_DQ<13>
  VSS53  = GND
  DQ16_B  = M_H_CPU0_SB_DQ<16>
  VSS54  = GND
  DQ17_B  = M_H_CPU0_SB_DQ<17>
  VSS55  = GND
  DQS2_B_T  = M_H_CPU0_SB_DQS_DP<2>
  DQS2_B_C  = M_H_CPU0_SB_DQS_DN<2>
  VSS56  = GND
  DQ20_B  = M_H_CPU0_SB_DQ<20>
  VSS57  = GND
  DQ21_B  = M_H_CPU0_SB_DQ<21>
  VSS58  = GND
  DQ24_B  = M_H_CPU0_SB_DQ<24>
  VSS59  = GND
  DQ25_B  = M_H_CPU0_SB_DQ<25>
  VSS60  = GND
  DQS3_B_T  = M_H_CPU0_SB_DQS_DP<3>
  DQS3_B_C  = M_H_CPU0_SB_DQS_DN<3>
  VSS61  = GND
  DQ28_B  = M_H_CPU0_SB_DQ<28>
  VSS62  = GND
  DQ29_B  = M_H_CPU0_SB_DQ<29>
  VSS63  = GND
  RFU1  = TP_CHH_CPU0_DIMM1_FRU_1
  VIN_BULK1  = P12V_S3_AUX_CPU0_NVDIMM
  VIN_BULK2  = P12V_S3_AUX_CPU0_NVDIMM
  \pwr_good||fail_n\  = PWRGD_CHH_CPU0_DIMM1
  HSA  = PD_CHH_CPU0_DIMM1_SAA
  RFU2  = TP_CHH_CPU0_DIMM1_FRU_2
  RFU3  = TP_CHH_CPU0_DIMM1_FRU_3
  VSS64  = GND
  DQ2_A  = M_H_CPU0_SA_DQ<2>
  VSS65  = GND
  DQ3_A  = M_H_CPU0_SA_DQ<3>
  VSS66  = GND
  \dqs5_a_c||tdqs5_a_c||dqs5_a_t||tdqs5_a_t\  = M_H_CPU0_SA_DQS_DN<5>
  \dqs5_a_t||tdqs5_a_t\  = M_H_CPU0_SA_DQS_DP<5>
  VSS67  = GND
  DQ6_A  = M_H_CPU0_SA_DQ<6>
  VSS68  = GND
  DQ7_A  = M_H_CPU0_SA_DQ<7>
  VSS69  = GND
  DQ10_A  = M_H_CPU0_SA_DQ<10>
  VSS70  = GND
  DQ11_A  = M_H_CPU0_SA_DQ<11>
  VSS71  = GND
  \dqs6_a_c||tdqs6_a_c||dqs6_a_t||tdqs6_a_t\  = M_H_CPU0_SA_DQS_DN<6>
  \dqs6_a_t||tdqs6_a_t\  = M_H_CPU0_SA_DQS_DP<6>
  VSS72  = GND
  DQ14_A  = M_H_CPU0_SA_DQ<14>
  VSS73  = GND
  DQ15_A  = M_H_CPU0_SA_DQ<15>
  VSS74  = GND
  DQ18_A  = M_H_CPU0_SA_DQ<18>
  VSS75  = GND
  DQ19_A  = M_H_CPU0_SA_DQ<19>
  VSS76  = GND
  \dqs7_a_c||tdqs7_a_c\  = M_H_CPU0_SA_DQS_DN<7>
  \dqs7_a_t||tdqs7_a_t\  = M_H_CPU0_SA_DQS_DP<7>
  VSS77  = GND
  DQ22_A  = M_H_CPU0_SA_DQ<22>
  VSS78  = GND
  DQ23_A  = M_H_CPU0_SA_DQ<23>
  VSS79  = GND
  DQ26_A  = M_H_CPU0_SA_DQ<26>
  VSS80  = GND
  DQ27_A  = M_H_CPU0_SA_DQ<27>
  VSS81  = GND
  \dqs8_a_c||tdqs8_a_c\  = M_H_CPU0_SA_DQS_DN<8>
  \dqs8_a_t||tdqs8_a_t\  = M_H_CPU0_SA_DQS_DP<8>
  VSS82  = GND
  DQ30_A  = M_H_CPU0_SA_DQ<30>
  VSS83  = GND
  DQ31_A  = M_H_CPU0_SA_DQ<31>
  VSS84  = GND
  CB2_A  = M_H_CPU0_SA_CB<2>
  VSS85  = GND
  CB3_A  = M_H_CPU0_SA_CB<3>
  VSS86  = GND
  \dqs9_a_c||tdqs9_a_c\  = M_H_CPU0_SA_DQS_DN<9>
  \dqs9_a_t||tdqs9_a_t\  = M_H_CPU0_SA_DQS_DP<9>
  VSS87  = GND
  CB6_A  = M_H_CPU0_SA_CB<6>
  VSS88  = GND
  CB7_A  = M_H_CPU0_SA_CB<7>
  VSS89  = GND
  RESET_N  = RST_M_GH_CPU0_FPGA_N
  VSS90  = GND
  CS1_A_N  = M_H_CPU0_SA_CS_N<1>
  VSS91  = GND
  CA1_A  = M_H_CPU0_SA_CA<1>
  VSS92  = GND
  CA3_A  = M_H_CPU0_SA_CA<3>
  VSS93  = GND
  CA5_A  = M_H_CPU0_SA_CA<5>
  VSS94  = GND
  CK_T  = M_H_CPU0_CLK_DP<0>
  CK_C  = M_H_CPU0_CLK_DN<0>
  VSS95  = GND
  RFU4  = TP_CHH_CPU0_DIMM1_FRU_4
  CA1_B  = M_H_CPU0_SB_CA<1>
  VSS96  = GND
  CA3_B  = M_H_CPU0_SB_CA<3>
  VSS97  = GND
  CA5_B  = M_H_CPU0_SB_CA<5>
  VSS98  = GND
  PAR_B  = M_H_CPU0_SB_PAR
  VSS99  = GND
  CS1_B_N  = M_H_CPU0_SB_CS_N<1>
  VSS100  = GND
  RFU5  = TP_CHH_CPU0_DIMM1_FRU_5
  RFU6  = TP_CHH_CPU0_DIMM1_FRU_6
  VSS101  = GND
  CB6_B  = M_H_CPU0_SB_CB<6>
  VSS102  = GND
  CB7_B  = M_H_CPU0_SB_CB<7>
  VSS103  = GND
  DQS4_B_C  = M_H_CPU0_SB_DQS_DN<4>
  DQS4_B_T  = M_H_CPU0_SB_DQS_DP<4>
  VSS104  = GND
  CB2_B  = M_H_CPU0_SB_CB<2>
  VSS105  = GND
  CB3_B  = M_H_CPU0_SB_CB<3>
  VSS106  = GND
  DQ2_B  = M_H_CPU0_SB_DQ<2>
  VSS107  = GND
  DQ3_B  = M_H_CPU0_SB_DQ<3>
  VSS108  = GND
  \dqs5_b_c||tdqs5_b_c\  = M_H_CPU0_SB_DQS_DN<5>
  \dqs5_b_t||tdqs5_b_t\  = M_H_CPU0_SB_DQS_DP<5>
  VSS109  = GND
  DQ6_B  = M_H_CPU0_SB_DQ<6>
  VSS110  = GND
  DQ7_B  = M_H_CPU0_SB_DQ<7>
  VSS111  = GND
  DQ10_B  = M_H_CPU0_SB_DQ<10>
  VSS112  = GND
  DQ11_B  = M_H_CPU0_SB_DQ<11>
  VSS113  = GND
  \dqs6_b_c||tdqs6_b_c\  = M_H_CPU0_SB_DQS_DN<6>
  \dqs6_b_t||tdqs6_b_t\  = M_H_CPU0_SB_DQS_DP<6>
  VSS114  = GND
  DQ14_B  = M_H_CPU0_SB_DQ<14>
  VSS115  = GND
  DQ15_B  = M_H_CPU0_SB_DQ<15>
  VSS116  = GND
  DQ18_B  = M_H_CPU0_SB_DQ<18>
  VSS117  = GND
  DQ19_B  = M_H_CPU0_SB_DQ<19>
  VSS118  = GND
  \dqs7_b_c||tdqs7_b_c\  = M_H_CPU0_SB_DQS_DN<7>
  \dqs7_b_t||tdqs7_b_t\  = M_H_CPU0_SB_DQS_DP<7>
  VSS119  = GND
  DQ22_B  = M_H_CPU0_SB_DQ<22>
  VSS120  = GND
  DQ23_B  = M_H_CPU0_SB_DQ<23>
  VSS121  = GND
  DQ26_B  = M_H_CPU0_SB_DQ<26>
  VSS122  = GND
  DQ27_B  = M_H_CPU0_SB_DQ<27>
  VSS123  = GND
  \dqs8_b_c||tdqs8_b_c\  = M_H_CPU0_SB_DQS_DN<8>
  \dqs8_b_t||tdqs8_b_t\  = M_H_CPU0_SB_DQS_DP<8>
  VSS124  = GND
  DQ30_B  = M_H_CPU0_SB_DQ<30>
  VSS125  = GND
  DQ31_B  = M_H_CPU0_SB_DQ<31>
  VSS126  = GND
  G1  = GND
  G2  = GND
  G3  = GND

(kicad_pcb
	(version 20260206)
	(generator "pcbnew")
	(generator_version "10.0")
	(general
		(thickness 1.6)
		(legacy_teardrops no)
	)
	(paper "A4")
	(title_block
		(title "03242023_DA0F0TMBIJ0_F0T_Motherboard_J_brd_V01_OCP.brd")
		(comment 1 "Grand Teton / footprint 2194 of 6105 (J15), pads 46-91 of 291")
	)
	(layers
		(0 "F.Cu" signal "TOP")
		(4 "In1.Cu" signal "GND")
		(6 "In2.Cu" signal "IN1")
		(8 "In3.Cu" signal "GND1")
		(10 "In4.Cu" signal "IN2")
		(12 "In5.Cu" signal "GND2")
		(14 "In6.Cu" signal "IN3")
		(16 "In7.Cu" signal "GND3")
		(18 "In8.Cu" signal "VCC")
		(20 "In9.Cu" signal "VCC1")
		(22 "In10.Cu" signal "GND4")
		(24 "In11.Cu" signal "IN4")
		(26 "In12.Cu" signal "GND5")
		(28 "In13.Cu" signal "IN5")
		(30 "In14.Cu" signal "GND6")
		(32 "In15.Cu" signal "IN6")
		(34 "In16.Cu" signal "GND7")
		(2 "B.Cu" signal "BOTTOM")
		(9 "F.Adhes" user "F.Adhesive")
		(11 "B.Adhes" user "B.Adhesive")
		(13 "F.Paste" user "Package Geometry/Pastemask Top")
		(15 "B.Paste" user "Package Geometry/Pastemask Bottom")
		(5 "F.SilkS" user "Ref Des/Silkscreen Top")
		(7 "B.SilkS" user "Ref Des/Silkscreen Bottom")
		(1 "F.Mask" user "Board Geometry/Soldermask Top")
		(3 "B.Mask" user "Board Geometry/Soldermask Bottom")
		(17 "Dwgs.User" user "User.Drawings")
		(19 "Cmts.User" user "User.Comments")
		(21 "Eco1.User" user "User.Eco1")
		(23 "Eco2.User" user "User.Eco2")
		(25 "Edge.Cuts" user "Board Geometry/Outline")
		(27 "Margin" user)
		(31 "F.CrtYd" user "Package Geometry/Place Bound Top")
		(29 "B.CrtYd" user "Package Geometry/Place Bound Bottom")
		(35 "F.Fab" user "Ref Des/Assembly Top")
		(33 "B.Fab" user "Ref Des/Assembly Bottom")
	)
	(footprint ""
		(layer "F.Cu")
		(at 461.609948 -258.091686)
		(property "Reference" "J15"
			(at 3.019552 -81.652872 0)
			(unlocked yes)
			(layer "F.SilkS")
			(effects
				(font
					(size 0.7874 0.5842)
					(thickness 0.1524)
				)
				(justify left)
			)
		)
		(property "Value" ""
			(at 0 0 0)
			(layer "F.Fab")
			(effects
				(font
					(size 1.27 1.27)
				)
			)
		)
		(duplicate_pad_numbers_are_jumpers no)
		(pad "46" smd rect
			(at -2.050034 -25.07488 270)
			(size 0.519938 1.4986)
			(layers "F.Cu" "F.Mask" "F.Paste")
			(net "GND")
		)
		(pad "47" smd rect
			(at -2.050034 -24.224996 270)
			(size 0.519938 1.4986)
			(layers "F.Cu" "F.Mask" "F.Paste")
			(net "M_H_CPU0_SA_DQ<28>")
		)
		(pad "48" smd rect
			(at -2.050034 -23.375112 270)
			(size 0.519938 1.4986)
			(layers "F.Cu" "F.Mask" "F.Paste")
			(net "GND")
		)
		(pad "49" smd rect
			(at -2.050034 -22.524974 270)
			(size 0.519938 1.4986)
			(layers "F.Cu" "F.Mask" "F.Paste")
			(net "M_H_CPU0_SA_DQ<29>")
		)
		(pad "50" smd rect
			(at -2.050034 -21.67509 270)
			(size 0.519938 1.4986)
			(layers "F.Cu" "F.Mask" "F.Paste")
			(net "GND")
		)
		(pad "51" smd rect
			(at -2.050034 -20.824952 270)
			(size 0.519938 1.4986)
			(layers "F.Cu" "F.Mask" "F.Paste")
			(net "M_H_CPU0_SA_CB<0>")
		)
		(pad "52" smd rect
			(at -2.050034 -19.975068 270)
			(size 0.519938 1.4986)
			(layers "F.Cu" "F.Mask" "F.Paste")
			(net "GND")
		)
		(pad "53" smd rect
			(at -2.050034 -19.12493 270)
			(size 0.519938 1.4986)
			(layers "F.Cu" "F.Mask" "F.Paste")
			(net "M_H_CPU0_SA_CB<1>")
		)
		(pad "54" smd rect
			(at -2.050034 -18.275046 270)
			(size 0.519938 1.4986)
			(layers "F.Cu" "F.Mask" "F.Paste")
			(net "GND")
		)
		(pad "55" smd rect
			(at -2.050034 -17.424908 270)
			(size 0.519938 1.4986)
			(layers "F.Cu" "F.Mask" "F.Paste")
			(net "M_H_CPU0_SA_DQS_DP<4>")
		)
		(pad "56" smd rect
			(at -2.050034 -16.575024 270)
			(size 0.519938 1.4986)
			(layers "F.Cu" "F.Mask" "F.Paste")
			(net "M_H_CPU0_SA_DQS_DN<4>")
		)
		(pad "57" smd rect
			(at -2.050034 -15.724886 270)
			(size 0.519938 1.4986)
			(layers "F.Cu" "F.Mask" "F.Paste")
			(net "GND")
		)
		(pad "58" smd rect
			(at -2.050034 -14.875002 270)
			(size 0.519938 1.4986)
			(layers "F.Cu" "F.Mask" "F.Paste")
			(net "M_H_CPU0_SA_CB<4>")
		)
		(pad "59" smd rect
			(at -2.050034 -14.025118 270)
			(size 0.519938 1.4986)
			(layers "F.Cu" "F.Mask" "F.Paste")
			(net "GND")
		)
		(pad "60" smd rect
			(at -2.050034 -13.17498 270)
			(size 0.519938 1.4986)
			(layers "F.Cu" "F.Mask" "F.Paste")
			(net "M_H_CPU0_SA_CB<5>")
		)
		(pad "61" smd rect
			(at -2.050034 -12.325096 270)
			(size 0.519938 1.4986)
			(layers "F.Cu" "F.Mask" "F.Paste")
			(net "GND")
		)
		(pad "62" smd rect
			(at -2.050034 -11.474958 270)
			(size 0.519938 1.4986)
			(layers "F.Cu" "F.Mask" "F.Paste")
			(net "M_H_CPU0_ALERT_N")
		)
		(pad "63" smd rect
			(at -2.050034 -10.625074 270)
			(size 0.519938 1.4986)
			(layers "F.Cu" "F.Mask" "F.Paste")
			(net "GND")
		)
		(pad "64" smd rect
			(at -2.050034 -9.774936 270)
			(size 0.519938 1.4986)
			(layers "F.Cu" "F.Mask" "F.Paste")
			(net "M_H_CPU0_SA_CS_N<0>")
		)
		(pad "65" smd rect
			(at -2.050034 -8.925052 270)
			(size 0.519938 1.4986)
			(layers "F.Cu" "F.Mask" "F.Paste")
			(net "GND")
		)
		(pad "66" smd rect
			(at -2.050034 -8.074914 270)
			(size 0.519938 1.4986)
			(layers "F.Cu" "F.Mask" "F.Paste")
			(net "M_H_CPU0_SA_CA<0>")
		)
		(pad "67" smd rect
			(at -2.050034 -7.22503 270)
			(size 0.519938 1.4986)
			(layers "F.Cu" "F.Mask" "F.Paste")
			(net "GND")
		)
		(pad "68" smd rect
			(at -2.050034 -6.374892 270)
			(size 0.519938 1.4986)
			(layers "F.Cu" "F.Mask" "F.Paste")
			(net "M_H_CPU0_SA_CA<2>")
		)
		(pad "69" smd rect
			(at -2.050034 -5.525008 270)
			(size 0.519938 1.4986)
			(layers "F.Cu" "F.Mask" "F.Paste")
			(net "GND")
		)
		(pad "70" smd rect
			(at -2.050034 -4.675124 270)
			(size 0.519938 1.4986)
			(layers "F.Cu" "F.Mask" "F.Paste")
			(net "M_H_CPU0_SA_CA<4>")
		)
		(pad "71" smd rect
			(at -2.050034 -3.824986 270)
			(size 0.519938 1.4986)
			(layers "F.Cu" "F.Mask" "F.Paste")
			(net "GND")
		)
		(pad "72" smd rect
			(at -2.050034 -2.975102 270)
			(size 0.519938 1.4986)
			(layers "F.Cu" "F.Mask" "F.Paste")
			(net "M_H_CPU0_SA_CA<6>")
		)
		(pad "73" smd rect
			(at -2.050034 -2.124964 270)
			(size 0.519938 1.4986)
			(layers "F.Cu" "F.Mask" "F.Paste")
			(net "GND")
		)
		(pad "74" smd rect
			(at -2.050034 -1.27508 270)
			(size 0.519938 1.4986)
			(layers "F.Cu" "F.Mask" "F.Paste")
			(net "M_H_CPU0_SA_PAR")
		)
		(pad "75" smd rect
			(at -2.050034 -0.424942 270)
			(size 0.519938 1.4986)
			(layers "F.Cu" "F.Mask" "F.Paste")
			(net "GND")
		)
		(pad "76" smd rect
			(at -2.050034 5.525008 270)
			(size 0.519938 1.4986)
			(layers "F.Cu" "F.Mask" "F.Paste")
			(net "M_H_CPU0_SB_CA<0>")
		)
		(pad "77" smd rect
			(at -2.050034 6.374892 270)
			(size 0.519938 1.4986)
			(layers "F.Cu" "F.Mask" "F.Paste")
			(net "GND")
		)
		(pad "78" smd rect
			(at -2.050034 7.22503 270)
			(size 0.519938 1.4986)
			(layers "F.Cu" "F.Mask" "F.Paste")
			(net "M_H_CPU0_SB_CA<2>")
		)
		(pad "79" smd rect
			(at -2.050034 8.074914 270)
			(size 0.519938 1.4986)
			(layers "F.Cu" "F.Mask" "F.Paste")
			(net "GND")
		)
		(pad "80" smd rect
			(at -2.050034 8.925052 270)
			(size 0.519938 1.4986)
			(layers "F.Cu" "F.Mask" "F.Paste")
			(net "M_H_CPU0_SB_CA<4>")
		)
		(pad "81" smd rect
			(at -2.050034 9.774936 270)
			(size 0.519938 1.4986)
			(layers "F.Cu" "F.Mask" "F.Paste")
			(net "GND")
		)
		(pad "82" smd rect
			(at -2.050034 10.625074 270)
			(size 0.519938 1.4986)
			(layers "F.Cu" "F.Mask" "F.Paste")
			(net "M_H_CPU0_SB_CA<6>")
		)
		(pad "83" smd rect
			(at -2.050034 11.474958 270)
			(size 0.519938 1.4986)
			(layers "F.Cu" "F.Mask" "F.Paste")
			(net "GND")
		)
		(pad "84" smd rect
			(at -2.050034 12.325096 270)
			(size 0.519938 1.4986)
			(layers "F.Cu" "F.Mask" "F.Paste")
			(net "M_H_CPU0_SB_CS_N<0>")
		)
		(pad "85" smd rect
			(at -2.050034 13.17498 270)
			(size 0.519938 1.4986)
			(layers "F.Cu" "F.Mask" "F.Paste")
			(net "GND")
		)
		(pad "86" smd rect
			(at -2.050034 14.025118 270)
			(size 0.519938 1.4986)
			(layers "F.Cu" "F.Mask" "F.Paste")
			(net "M_H_CPU0_SA_RSP<0>")
		)
		(pad "87" smd rect
			(at -2.050034 14.875002 270)
			(size 0.519938 1.4986)
			(layers "F.Cu" "F.Mask" "F.Paste")
			(net "M_H_CPU0_SB_RSP<0>")
		)
		(pad "88" smd rect
			(at -2.050034 15.724886 270)
			(size 0.519938 1.4986)
			(layers "F.Cu" "F.Mask" "F.Paste")
			(net "GND")
		)
		(pad "89" smd rect
			(at -2.050034 16.575024 270)
			(size 0.519938 1.4986)
			(layers "F.Cu" "F.Mask" "F.Paste")
			(net "M_H_CPU0_SB_CB<4>")
		)
		(pad "90" smd rect
			(at -2.050034 17.424908 270)
			(size 0.519938 1.4986)
			(layers "F.Cu" "F.Mask" "F.Paste")
			(net "GND")
		)
		(pad "91" smd rect
			(at -2.050034 18.275046 270)
			(size 0.519938 1.4986)
			(layers "F.Cu" "F.Mask" "F.Paste")
			(net "M_H_CPU0_SB_CB<5>")
		)
	)
)
